FILE_TYPE = CONNECTIVITY;
{Allegro Design Entry HDL 17.2-2016 S081 (4005846) 1/11/2022}
"PAGE_NUMBER" = 99;
0"NC";
1"P3V3_AUX\g";
2"P12V_S3_AUX_CPU1_NVDIMM\g";
3"P12V_S3_AUX_CPU1_NVDIMM\g";
4"P3V3_AUX\g";
5"GND\g";
6"GND\g";
7"GND\g";
8"GND\g";
9"GND\g";
10"M_A_CPU1_SA_DQ<31:0>";
11"M_A_CPU1_SA_CB<7:0>";
12"M_A_CPU1_SB_CB<7:0>";
13"M_A_CPU1_SA_CA<6:0>";
14"M_A_CPU1_SB_CA<6:0>";
15"M_A_CPU1_SB_DQ<31:0>";
16"M_A_CPU1_SB_DQS_DP<9:0>";
17"M_A_CPU1_SA_DQS_DP<9:0>";
18"M_A_CPU1_SB_DQS_DN<9:0>";
19"M_A_CPU1_SA_DQS_DN<9:0>";
20"PD_CHA_CPU1_DIMM2_SAA";
21"I3C_SPD_DDRABCD_CPU1_LVC1_SDA";
22"I3C_SPD_DDRABCD_CPU1_LVC1_SCL_R2";
23"M_A_CPU1_ALERT_N";
24"RST_M_AB_CPU1_FPGA_N";
25"I3C_SPD_DDRABCD_CPU1_LVC1_SCL";
26"M_A_CPU1_SB_DQS_DN<5>";
27"M_A_CPU1_SA_DQS_DN<9>";
28"M_A_CPU1_SA_DQS_DN<8>";
29"M_A_CPU1_SA_DQS_DN<7>";
30"M_A_CPU1_SA_DQS_DN<5>";
31"M_A_CPU1_SA_DQS_DN<6>";
32"M_A_CPU1_SA_DQS_DN<4>";
33"M_A_CPU1_SA_DQS_DN<3>";
34"M_A_CPU1_SA_DQS_DN<2>";
35"M_A_CPU1_SA_DQS_DN<1>";
36"M_A_CPU1_SA_DQS_DN<0>";
37"M_A_CPU1_SB_DQS_DN<9>";
38"M_A_CPU1_SB_DQS_DN<8>";
39"M_A_CPU1_SB_DQS_DN<7>";
40"M_A_CPU1_SB_DQS_DN<6>";
41"M_A_CPU1_SB_DQS_DN<4>";
42"M_A_CPU1_SB_DQS_DN<3>";
43"M_A_CPU1_SB_DQS_DN<2>";
44"M_A_CPU1_SB_DQS_DN<0>";
45"M_A_CPU1_SB_DQS_DN<1>";
46"M_A_CPU1_SA_DQS_DP<9>";
47"M_A_CPU1_SA_DQS_DP<8>";
48"M_A_CPU1_SA_DQS_DP<7>";
49"M_A_CPU1_SA_DQS_DP<6>";
50"M_A_CPU1_SA_DQS_DP<5>";
51"M_A_CPU1_SA_DQS_DP<4>";
52"M_A_CPU1_SA_DQS_DP<3>";
53"M_A_CPU1_SA_DQS_DP<2>";
54"M_A_CPU1_SA_DQS_DP<1>";
55"M_A_CPU1_SA_DQS_DP<0>";
56"M_A_CPU1_SB_DQS_DP<9>";
57"M_A_CPU1_SB_DQS_DP<8>";
58"M_A_CPU1_SB_DQS_DP<7>";
59"M_A_CPU1_SB_DQS_DP<6>";
60"M_A_CPU1_SB_DQS_DP<5>";
61"M_A_CPU1_SB_DQS_DP<4>";
62"M_A_CPU1_SB_DQS_DP<2>";
63"M_A_CPU1_SB_DQS_DP<3>";
64"M_A_CPU1_SB_DQS_DP<1>";
65"M_A_CPU1_SB_DQS_DP<0>";
66"M_A_CPU1_SB_DQ<27>";
67"M_A_CPU1_SB_CB<1>";
68"M_A_CPU1_SA_PAR";
69"M_A_CPU1_SB_PAR";
70"M_A_CPU1_SA_DQ<4>";
71"M_A_CPU1_SB_CS_N<2>";
72"M_A_CPU1_SA_DQ<8>";
73"M_A_CPU1_SB_DQ<24>";
74"TP_CHA_CPU1_DIMM2_FRU_0";
75"TP_CHA_CPU1_DIMM2_FRU_1";
76"TP_CHA_CPU1_DIMM2_FRU_2";
77"TP_CHA_CPU1_DIMM2_FRU_3";
78"TP_CHA_CPU1_DIMM2_FRU_4";
79"TP_CHA_CPU1_DIMM2_FRU_5";
80"TP_CHA_CPU1_DIMM2_FRU_6";
81"PWRGD_CHA_CPU1_DIMM2";
82"M_A_CPU1_SB_RSP<1>";
83"M_A_CPU1_SA_RSP<1>";
84"M_A_CPU1_SB_DQ<0>";
85"M_A_CPU1_SB_DQ<1>";
86"M_A_CPU1_SB_DQ<2>";
87"M_A_CPU1_SB_DQ<3>";
88"M_A_CPU1_SB_DQ<4>";
89"M_A_CPU1_SB_DQ<5>";
90"M_A_CPU1_SB_DQ<6>";
91"M_A_CPU1_SB_DQ<7>";
92"M_A_CPU1_SB_DQ<8>";
93"M_A_CPU1_SB_DQ<9>";
94"M_A_CPU1_SB_DQ<10>";
95"M_A_CPU1_SB_DQ<11>";
96"M_A_CPU1_SB_DQ<12>";
97"M_A_CPU1_SB_DQ<13>";
98"M_A_CPU1_SB_DQ<14>";
99"M_A_CPU1_SB_DQ<15>";
100"M_A_CPU1_SB_DQ<16>";
101"M_A_CPU1_SB_DQ<17>";
102"M_A_CPU1_SB_DQ<18>";
103"M_A_CPU1_SB_DQ<19>";
104"M_A_CPU1_SB_DQ<20>";
105"M_A_CPU1_SB_DQ<21>";
106"M_A_CPU1_SB_DQ<22>";
107"M_A_CPU1_SB_DQ<23>";
108"M_A_CPU1_SB_DQ<25>";
109"M_A_CPU1_SB_DQ<26>";
110"M_A_CPU1_SB_DQ<28>";
111"M_A_CPU1_SB_DQ<29>";
112"M_A_CPU1_SB_DQ<30>";
113"M_A_CPU1_SB_DQ<31>";
114"M_A_CPU1_SA_DQ<0>";
115"M_A_CPU1_SA_DQ<1>";
116"M_A_CPU1_SA_DQ<2>";
117"M_A_CPU1_SA_DQ<3>";
118"M_A_CPU1_SA_DQ<5>";
119"M_A_CPU1_SA_DQ<6>";
120"M_A_CPU1_SA_DQ<7>";
121"M_A_CPU1_SA_DQ<9>";
122"M_A_CPU1_SA_DQ<10>";
123"M_A_CPU1_SA_DQ<11>";
124"M_A_CPU1_SA_DQ<12>";
125"M_A_CPU1_SA_DQ<13>";
126"M_A_CPU1_SA_DQ<14>";
127"M_A_CPU1_SA_DQ<15>";
128"M_A_CPU1_SA_DQ<16>";
129"M_A_CPU1_SA_DQ<17>";
130"M_A_CPU1_SA_DQ<18>";
131"M_A_CPU1_SA_DQ<19>";
132"M_A_CPU1_SA_DQ<20>";
133"M_A_CPU1_SA_DQ<21>";
134"M_A_CPU1_SA_DQ<22>";
135"M_A_CPU1_SA_DQ<23>";
136"M_A_CPU1_SA_DQ<24>";
137"M_A_CPU1_SA_DQ<25>";
138"M_A_CPU1_SA_DQ<26>";
139"M_A_CPU1_SA_DQ<27>";
140"M_A_CPU1_SA_DQ<28>";
141"M_A_CPU1_SA_DQ<29>";
142"M_A_CPU1_SA_DQ<30>";
143"M_A_CPU1_SB_CS_N<3>";
144"M_A_CPU1_SA_CS_N<3>";
145"M_A_CPU1_SA_CS_N<2>";
146"M_A_CPU1_CLK_DP<1>";
147"M_A_CPU1_CLK_DN<1>";
148"M_A_CPU1_SB_CB<0>";
149"M_A_CPU1_SB_CB<2>";
150"M_A_CPU1_SB_CB<3>";
151"M_A_CPU1_SB_CB<4>";
152"M_A_CPU1_SB_CB<5>";
153"M_A_CPU1_SB_CB<6>";
154"M_A_CPU1_SA_CB<0>";
155"M_A_CPU1_SA_CB<2>";
156"M_A_CPU1_SA_CB<3>";
157"M_A_CPU1_SA_CB<5>";
158"M_A_CPU1_SA_CB<6>";
159"M_A_CPU1_SB_CA<6>";
160"M_A_CPU1_SA_CA<6>";
161"M_A_CPU1_SB_CA<5>";
162"M_A_CPU1_SA_CA<5>";
163"M_A_CPU1_SB_CA<4>";
164"M_A_CPU1_SA_CA<4>";
165"M_A_CPU1_SB_CA<3>";
166"M_A_CPU1_SA_CA<3>";
167"M_A_CPU1_SB_CA<2>";
168"M_A_CPU1_SA_CA<2>";
169"M_A_CPU1_SB_CA<1>";
170"M_A_CPU1_SA_CA<1>";
171"M_A_CPU1_SB_CA<0>";
172"M_A_CPU1_SA_CA<0>";
173"M_A_CPU1_SB_CB<7>";
174"M_A_CPU1_SA_CB<1>";
175"M_A_CPU1_SA_CB<4>";
176"M_A_CPU1_SA_CB<7>";
177"M_A_CPU1_SA_DQ<31>";
178"PD_CHA_CPU1_DIMM2_SAA";
%"UNIVERSAL_GND"
"1","(-1650,-575)","0","logical_power","I1";
;
HDL_POWER"GND"
CDS_LIB"logical_power";
"A"9;
%"TAP"
"1","(-225,3050)","0","standard","I100";
;
CDS_LIB"standard"
BODY_TYPE"PLUMBING"
HDL_TAP"TRUE";
"B \NAC \NWC"10;
"S \NAC"
BN"16"128;
%"TAP"
"1","(-225,3150)","0","standard","I101";
;
CDS_LIB"standard"
BODY_TYPE"PLUMBING"
HDL_TAP"TRUE";
"B \NAC \NWC"10;
"S \NAC"
BN"18"130;
%"TAP"
"1","(-225,3100)","0","standard","I102";
;
CDS_LIB"standard"
BODY_TYPE"PLUMBING"
HDL_TAP"TRUE";
"B \NAC \NWC"10;
"S \NAC"
BN"17"129;
%"TAP"
"1","(-225,3200)","0","standard","I103";
;
CDS_LIB"standard"
BODY_TYPE"PLUMBING"
HDL_TAP"TRUE";
"B \NAC \NWC"10;
"S \NAC"
BN"19"131;
%"TAP"
"1","(-225,3300)","0","standard","I104";
;
CDS_LIB"standard"
BODY_TYPE"PLUMBING"
HDL_TAP"TRUE";
"B \NAC \NWC"10;
"S \NAC"
BN"21"133;
%"TAP"
"1","(-225,3250)","0","standard","I105";
;
CDS_LIB"standard"
BODY_TYPE"PLUMBING"
HDL_TAP"TRUE";
"B \NAC \NWC"10;
"S \NAC"
BN"20"132;
%"TAP"
"1","(-225,3400)","0","standard","I106";
;
CDS_LIB"standard"
BODY_TYPE"PLUMBING"
HDL_TAP"TRUE";
"B \NAC \NWC"10;
"S \NAC"
BN"23"135;
%"TAP"
"1","(-225,3350)","0","standard","I107";
;
CDS_LIB"standard"
BODY_TYPE"PLUMBING"
HDL_TAP"TRUE";
"B \NAC \NWC"10;
"S \NAC"
BN"22"134;
%"TAP"
"1","(-225,3500)","0","standard","I108";
;
CDS_LIB"standard"
BODY_TYPE"PLUMBING"
HDL_TAP"TRUE";
"B \NAC \NWC"10;
"S \NAC"
BN"25"137;
%"TAP"
"1","(-225,3450)","0","standard","I109";
;
CDS_LIB"standard"
BODY_TYPE"PLUMBING"
HDL_TAP"TRUE";
"B \NAC \NWC"10;
"S \NAC"
BN"24"136;
%"TAP"
"1","(-225,3550)","0","standard","I110";
;
CDS_LIB"standard"
BODY_TYPE"PLUMBING"
HDL_TAP"TRUE";
"B \NAC \NWC"10;
"S \NAC"
BN"26"138;
%"TAP"
"1","(-225,3600)","0","standard","I111";
;
CDS_LIB"standard"
BODY_TYPE"PLUMBING"
HDL_TAP"TRUE";
"B \NAC \NWC"10;
"S \NAC"
BN"27"139;
%"TAP"
"1","(-225,3650)","0","standard","I112";
;
CDS_LIB"standard"
BODY_TYPE"PLUMBING"
HDL_TAP"TRUE";
"B \NAC \NWC"10;
"S \NAC"
BN"28"140;
%"TAP"
"1","(-1875,3750)","2","standard","I114";
;
CDS_LIB"standard"
BODY_TYPE"PLUMBING"
HDL_TAP"TRUE";
"B \NAC \NWC"13;
"S \NAC"
BN"5"162;
%"TAP"
"1","(-1875,3700)","2","standard","I115";
;
CDS_LIB"standard"
BODY_TYPE"PLUMBING"
HDL_TAP"TRUE";
"B \NAC \NWC"13;
"S \NAC"
BN"4"164;
%"TAP"
"1","(-1875,3800)","2","standard","I116";
;
CDS_LIB"standard"
BODY_TYPE"PLUMBING"
HDL_TAP"TRUE";
"B \NAC \NWC"13;
"S \NAC"
BN"6"160;
%"TAP"
"1","(-225,3700)","0","standard","I117";
;
CDS_LIB"standard"
BODY_TYPE"PLUMBING"
HDL_TAP"TRUE";
"B \NAC \NWC"10;
"S \NAC"
BN"29"141;
%"TAP"
"1","(-225,3750)","0","standard","I118";
;
CDS_LIB"standard"
BODY_TYPE"PLUMBING"
HDL_TAP"TRUE";
"B \NAC \NWC"10;
"S \NAC"
BN"30"142;
%"TAP"
"1","(-225,3800)","0","standard","I119";
;
CDS_LIB"standard"
BODY_TYPE"PLUMBING"
HDL_TAP"TRUE";
"B \NAC \NWC"10;
"S \NAC"
BN"31"177;
%"VCC_CORE"
"1","(-2700,1675)","0","logical_power","I12";
;
HDL_POWER"P3V3_AUX"
CDS_LIB"logical_power";
"A"1;
%"UNIVERSAL_GND"
"1","(1500,-450)","0","logical_power","I120";
;
HDL_POWER"GND"
CDS_LIB"logical_power";
"A"8;
%"UNIVERSAL_GND"
"1","(3125,-450)","0","logical_power","I121";
;
HDL_POWER"GND"
CDS_LIB"logical_power";
"A"7;
%"Q_CAP"
"1","(1500,-75)","0","pure_quanta","I122";
;
PART_NUMBER"CH5221MEB00"
VALUE"2.2UF"
TOLERANCE"20%"
MATERIAL"X6S"
VOLTAGE"6.3V"
PACK_TYPE"C0402"
$LOCATION"C53"
CDS_LIB"pure_quanta"
CDS_LOCATION"C53"
$SEC"1"
CDS_SEC"1";
"B"
$PN"2"8;
"A"
$PN"1"4;
%"VCC_CORE"
"1","(1500,250)","0","logical_power","I123";
;
HDL_POWER"P3V3_AUX"
CDS_LIB"logical_power";
"A"4;
%"Q_CAP"
"1","(2500,-75)","0","pure_quanta","I126";
;
PART_NUMBER"CH6103KEA00"
VALUE"10UF"
PACK_TYPE"C0805"
TOLERANCE"10%"
VOLTAGE"16V"
MATERIAL"X6S"
$LOCATION"C54"
CDS_LIB"pure_quanta"
CDS_LOCATION"C54"
$SEC"1"
CDS_SEC"1";
"B"
$PN"2"7;
"A"
$PN"1"3;
%"VCC_CORE"
"1","(2500,250)","0","logical_power","I127";
;
HDL_POWER"P12V_S3_AUX_CPU1_NVDIMM"
CDS_LIB"logical_power";
"A"3;
%"Q_CAP"
"1","(3125,-75)","0","pure_quanta","I128";
;
PART_NUMBER"CH6103KEA00"
MATERIAL"X6S"
VALUE"10UF"
PACK_TYPE"C0805"
VOLTAGE"16V"
TOLERANCE"10%"
$LOCATION"C55"
CDS_LIB"pure_quanta"
CDS_LOCATION"C55"
$SEC"1"
CDS_SEC"1";
"B"
$PN"2"7;
"A"
$PN"1"3;
%"TAP"
"1","(2525,1850)","0","standard","I129";
;
CDS_LIB"standard"
BODY_TYPE"PLUMBING"
HDL_TAP"TRUE";
"B \NAC \NWC"16;
"S \NAC"
BN"0"65;
%"TAP"
"1","(2700,1900)","0","standard","I130";
;
CDS_LIB"standard"
BODY_TYPE"PLUMBING"
HDL_TAP"TRUE";
"B \NAC \NWC"18;
"S \NAC"
BN"1"45;
%"TAP"
"1","(2700,1800)","0","standard","I131";
;
CDS_LIB"standard"
BODY_TYPE"PLUMBING"
HDL_TAP"TRUE";
"B \NAC \NWC"18;
"S \NAC"
BN"0"44;
%"TAP"
"1","(2525,1950)","0","standard","I132";
;
CDS_LIB"standard"
BODY_TYPE"PLUMBING"
HDL_TAP"TRUE";
"B \NAC \NWC"16;
"S \NAC"
BN"1"64;
%"TAP"
"1","(2525,2150)","0","standard","I133";
;
CDS_LIB"standard"
BODY_TYPE"PLUMBING"
HDL_TAP"TRUE";
"B \NAC \NWC"16;
"S \NAC"
BN"3"63;
%"TAP"
"1","(2525,2050)","0","standard","I134";
;
CDS_LIB"standard"
BODY_TYPE"PLUMBING"
HDL_TAP"TRUE";
"B \NAC \NWC"16;
"S \NAC"
BN"2"62;
%"TAP"
"1","(2700,2000)","0","standard","I135";
;
CDS_LIB"standard"
BODY_TYPE"PLUMBING"
HDL_TAP"TRUE";
"B \NAC \NWC"18;
"S \NAC"
BN"2"43;
%"TAP"
"1","(2700,2100)","0","standard","I136";
;
CDS_LIB"standard"
BODY_TYPE"PLUMBING"
HDL_TAP"TRUE";
"B \NAC \NWC"18;
"S \NAC"
BN"3"42;
%"TAP"
"1","(2525,2250)","0","standard","I137";
;
CDS_LIB"standard"
BODY_TYPE"PLUMBING"
HDL_TAP"TRUE";
"B \NAC \NWC"16;
"S \NAC"
BN"4"61;
%"TAP"
"1","(2525,2350)","0","standard","I138";
;
CDS_LIB"standard"
BODY_TYPE"PLUMBING"
HDL_TAP"TRUE";
"B \NAC \NWC"16;
"S \NAC"
BN"5"60;
%"TAP"
"1","(2700,2200)","0","standard","I139";
;
CDS_LIB"standard"
BODY_TYPE"PLUMBING"
HDL_TAP"TRUE";
"B \NAC \NWC"18;
"S \NAC"
BN"4"41;
%"TAP"
"1","(2700,2300)","0","standard","I140";
;
CDS_LIB"standard"
BODY_TYPE"PLUMBING"
HDL_TAP"TRUE";
"B \NAC \NWC"18;
"S \NAC"
BN"5"26;
%"TAP"
"1","(2700,2400)","0","standard","I141";
;
CDS_LIB"standard"
BODY_TYPE"PLUMBING"
HDL_TAP"TRUE";
"B \NAC \NWC"18;
"S \NAC"
BN"6"40;
%"TAP"
"1","(2525,2450)","0","standard","I142";
;
CDS_LIB"standard"
BODY_TYPE"PLUMBING"
HDL_TAP"TRUE";
"B \NAC \NWC"16;
"S \NAC"
BN"6"59;
%"TAP"
"1","(2525,2650)","0","standard","I143";
;
CDS_LIB"standard"
BODY_TYPE"PLUMBING"
HDL_TAP"TRUE";
"B \NAC \NWC"16;
"S \NAC"
BN"8"57;
%"TAP"
"1","(2525,2550)","0","standard","I144";
;
CDS_LIB"standard"
BODY_TYPE"PLUMBING"
HDL_TAP"TRUE";
"B \NAC \NWC"16;
"S \NAC"
BN"7"58;
%"TAP"
"1","(2700,2500)","0","standard","I145";
;
CDS_LIB"standard"
BODY_TYPE"PLUMBING"
HDL_TAP"TRUE";
"B \NAC \NWC"18;
"S \NAC"
BN"7"39;
%"TAP"
"1","(2700,2600)","0","standard","I146";
;
CDS_LIB"standard"
BODY_TYPE"PLUMBING"
HDL_TAP"TRUE";
"B \NAC \NWC"18;
"S \NAC"
BN"8"38;
%"TAP"
"1","(2525,2750)","0","standard","I147";
;
CDS_LIB"standard"
BODY_TYPE"PLUMBING"
HDL_TAP"TRUE";
"B \NAC \NWC"16;
"S \NAC"
BN"9"56;
%"TAP"
"1","(2525,2900)","0","standard","I148";
;
CDS_LIB"standard"
BODY_TYPE"PLUMBING"
HDL_TAP"TRUE";
"B \NAC \NWC"17;
"S \NAC"
BN"0"55;
%"TAP"
"1","(2700,2700)","0","standard","I149";
;
CDS_LIB"standard"
BODY_TYPE"PLUMBING"
HDL_TAP"TRUE";
"B \NAC \NWC"18;
"S \NAC"
BN"9"37;
%"TAP"
"1","(2700,2850)","0","standard","I150";
;
CDS_LIB"standard"
BODY_TYPE"PLUMBING"
HDL_TAP"TRUE";
"B \NAC \NWC"19;
"S \NAC"
BN"0"36;
%"TAP"
"1","(2525,3000)","0","standard","I151";
;
CDS_LIB"standard"
BODY_TYPE"PLUMBING"
HDL_TAP"TRUE";
"B \NAC \NWC"17;
"S \NAC"
BN"1"54;
%"TAP"
"1","(2525,3100)","0","standard","I152";
;
CDS_LIB"standard"
BODY_TYPE"PLUMBING"
HDL_TAP"TRUE";
"B \NAC \NWC"17;
"S \NAC"
BN"2"53;
%"TAP"
"1","(2700,2950)","0","standard","I153";
;
CDS_LIB"standard"
BODY_TYPE"PLUMBING"
HDL_TAP"TRUE";
"B \NAC \NWC"19;
"S \NAC"
BN"1"35;
%"TAP"
"1","(2700,3050)","0","standard","I154";
;
CDS_LIB"standard"
BODY_TYPE"PLUMBING"
HDL_TAP"TRUE";
"B \NAC \NWC"19;
"S \NAC"
BN"2"34;
%"TAP"
"1","(2700,3150)","0","standard","I155";
;
CDS_LIB"standard"
BODY_TYPE"PLUMBING"
HDL_TAP"TRUE";
"B \NAC \NWC"19;
"S \NAC"
BN"3"33;
%"TAP"
"1","(2525,3300)","0","standard","I156";
;
CDS_LIB"standard"
BODY_TYPE"PLUMBING"
HDL_TAP"TRUE";
"B \NAC \NWC"17;
"S \NAC"
BN"4"51;
%"TAP"
"1","(2525,3200)","0","standard","I157";
;
CDS_LIB"standard"
BODY_TYPE"PLUMBING"
HDL_TAP"TRUE";
"B \NAC \NWC"17;
"S \NAC"
BN"3"52;
%"TAP"
"1","(2525,3400)","0","standard","I158";
;
CDS_LIB"standard"
BODY_TYPE"PLUMBING"
HDL_TAP"TRUE";
"B \NAC \NWC"17;
"S \NAC"
BN"5"50;
%"TAP"
"1","(2700,3250)","0","standard","I159";
;
CDS_LIB"standard"
BODY_TYPE"PLUMBING"
HDL_TAP"TRUE";
"B \NAC \NWC"19;
"S \NAC"
BN"4"32;
%"TAP"
"1","(2700,3350)","0","standard","I160";
;
CDS_LIB"standard"
BODY_TYPE"PLUMBING"
HDL_TAP"TRUE";
"B \NAC \NWC"19;
"S \NAC"
BN"5"30;
%"TAP"
"1","(2525,3500)","0","standard","I161";
;
CDS_LIB"standard"
BODY_TYPE"PLUMBING"
HDL_TAP"TRUE";
"B \NAC \NWC"17;
"S \NAC"
BN"6"49;
%"TAP"
"1","(2525,3600)","0","standard","I162";
;
CDS_LIB"standard"
BODY_TYPE"PLUMBING"
HDL_TAP"TRUE";
"B \NAC \NWC"17;
"S \NAC"
BN"7"48;
%"TAP"
"1","(2700,3450)","0","standard","I163";
;
CDS_LIB"standard"
BODY_TYPE"PLUMBING"
HDL_TAP"TRUE";
"B \NAC \NWC"19;
"S \NAC"
BN"6"31;
%"TAP"
"1","(2700,3550)","0","standard","I164";
;
CDS_LIB"standard"
BODY_TYPE"PLUMBING"
HDL_TAP"TRUE";
"B \NAC \NWC"19;
"S \NAC"
BN"7"29;
%"TAP"
"1","(2700,3650)","0","standard","I165";
;
CDS_LIB"standard"
BODY_TYPE"PLUMBING"
HDL_TAP"TRUE";
"B \NAC \NWC"19;
"S \NAC"
BN"8"28;
%"TAP"
"1","(2525,3800)","0","standard","I169";
;
CDS_LIB"standard"
BODY_TYPE"PLUMBING"
HDL_TAP"TRUE";
"B \NAC \NWC"17;
"S \NAC"
BN"9"46;
%"TAP"
"1","(2525,3700)","0","standard","I170";
;
CDS_LIB"standard"
BODY_TYPE"PLUMBING"
HDL_TAP"TRUE";
"B \NAC \NWC"17;
"S \NAC"
BN"8"47;
%"TAP"
"1","(2700,3750)","0","standard","I171";
;
CDS_LIB"standard"
BODY_TYPE"PLUMBING"
HDL_TAP"TRUE";
"B \NAC \NWC"19;
"S \NAC"
BN"9"27;
%"UNIVERSAL_GND"
"1","(4200,100)","0","logical_power","I174";
;
HDL_POWER"GND"
CDS_LIB"logical_power";
"A"6;
%"SCONN288_ADR50017P087CC"
"3","(5050,2175)","0","pure_quanta","I175";
;
PART_NUMBER"DFHST8FS460"
MATERIAL"IO"
VALUE"SCONN288_ADR50017-P087CC"
PART_TYPE"SMLF"
$LOCATION"J18"
CDS_LIB"pure_quanta"
CDS_LMAN_SYM_OUTLINE"-450,1775,450,-1775"
NEEDS_NO_SIZE"TRUE"
CDS_LOCATION"J18"
$SEC"3"
CDS_SEC"3";
"G3"
$PN"G3"5;
"G2"
$PN"G2"5;
"G1"
$PN"G1"5;
"VSS62"
$PN"141"5;
"VSS61"
$PN"139"5;
"VSS60"
$PN"136"5;
"VSS58"
$PN"132"5;
"VSS104"
$PN"240"6;
"VSS102"
$PN"235"6;
"VSS100"
$PN"230"6;
"VIN_BULK2"
$PN"146"2;
"VIN_BULK1"
$PN"145"2;
"VIN_BULK0"
$PN"1"2;
"VSS126"
$PN"288"6;
"VSS125"
$PN"286"6;
"VSS124"
$PN"284"6;
"VSS123"
$PN"281"6;
"VSS122"
$PN"279"6;
"VSS121"
$PN"277"6;
"VSS120"
$PN"275"6;
"VSS119"
$PN"273"6;
"VSS118"
$PN"270"6;
"VSS117"
$PN"268"6;
"VSS116"
$PN"266"6;
"VSS115"
$PN"264"6;
"VSS114"
$PN"262"6;
"VSS113"
$PN"259"6;
"VSS112"
$PN"257"6;
"VSS111"
$PN"255"6;
"VSS110"
$PN"253"6;
"VSS109"
$PN"251"6;
"VSS108"
$PN"248"6;
"VSS107"
$PN"246"6;
"VSS106"
$PN"244"6;
"VSS105"
$PN"242"6;
"VSS103"
$PN"237"6;
"VSS101"
$PN"233"6;
"VSS99"
$PN"228"6;
"VSS98"
$PN"226"6;
"VSS97"
$PN"224"6;
"VSS96"
$PN"222"6;
"VSS95"
$PN"219"6;
"VSS94"
$PN"216"6;
"VSS93"
$PN"214"6;
"VSS92"
$PN"212"6;
"VSS91"
$PN"210"6;
"VSS90"
$PN"208"6;
"VSS89"
$PN"206"6;
"VSS88"
$PN"204"6;
"VSS87"
$PN"202"6;
"VSS86"
$PN"199"6;
"VSS85"
$PN"197"6;
"VSS84"
$PN"195"6;
"VSS83"
$PN"193"6;
"VSS82"
$PN"191"6;
"VSS81"
$PN"188"6;
"VSS80"
$PN"186"6;
"VSS79"
$PN"184"6;
"VSS78"
$PN"182"6;
"VSS77"
$PN"180"6;
"VSS76"
$PN"177"6;
"VSS75"
$PN"175"6;
"VSS74"
$PN"173"6;
"VSS73"
$PN"171"6;
"VSS72"
$PN"169"6;
"VSS71"
$PN"166"6;
"VSS70"
$PN"164"6;
"VSS69"
$PN"162"6;
"VSS68"
$PN"160"6;
"VSS67"
$PN"158"6;
"VSS66"
$PN"155"6;
"VSS65"
$PN"153"6;
"VSS64"
$PN"151"6;
"VSS63"
$PN"143"5;
"VSS59"
$PN"134"5;
"VSS57"
$PN"130"5;
"VSS56"
$PN"128"5;
"VSS55"
$PN"125"5;
"VSS54"
$PN"123"5;
"VSS53"
$PN"121"5;
"VSS52"
$PN"119"5;
"VSS51"
$PN"117"5;
"VSS50"
$PN"114"5;
"VSS49"
$PN"112"5;
"VSS48"
$PN"110"5;
"VSS47"
$PN"108"5;
"VSS46"
$PN"106"5;
"VSS45"
$PN"103"5;
"VSS44"
$PN"101"5;
"VSS43"
$PN"99"5;
"VSS42"
$PN"97"5;
"VSS41"
$PN"95"5;
"VSS40"
$PN"92"5;
"VSS39"
$PN"90"5;
"VSS38"
$PN"88"5;
"VSS37"
$PN"85"5;
"VSS36"
$PN"83"5;
"VSS35"
$PN"81"5;
"VSS34"
$PN"79"5;
"VSS33"
$PN"77"5;
"VSS32"
$PN"75"5;
"VSS31"
$PN"73"5;
"VSS30"
$PN"71"5;
"VSS29"
$PN"69"5;
"VSS28"
$PN"67"5;
"VSS27"
$PN"65"5;
"VSS26"
$PN"63"5;
"VSS25"
$PN"61"5;
"VSS24"
$PN"59"5;
"VSS23"
$PN"57"5;
"VSS22"
$PN"54"5;
"VSS21"
$PN"52"5;
"VSS20"
$PN"50"5;
"VSS19"
$PN"48"5;
"VSS18"
$PN"46"5;
"VSS17"
$PN"43"5;
"VSS16"
$PN"41"5;
"VSS15"
$PN"39"5;
"VSS14"
$PN"37"5;
"VSS13"
$PN"35"5;
"VSS12"
$PN"32"5;
"VSS11"
$PN"30"5;
"VSS10"
$PN"28"5;
"VSS9"
$PN"26"5;
"VSS8"
$PN"24"5;
"VSS7"
$PN"21"5;
"VSS6"
$PN"19"5;
"VSS5"
$PN"17"5;
"VSS4"
$PN"15"5;
"VSS3"
$PN"13"5;
"VSS2"
$PN"10"5;
"VSS1"
$PN"8"5;
"VSS0"
$PN"6"5;
%"UNIVERSAL_GND"
"1","(5900,100)","0","logical_power","I176";
;
HDL_POWER"GND"
CDS_LIB"logical_power";
"A"5;
%"VCC_CORE"
"1","(4200,4350)","0","logical_power","I177";
;
HDL_POWER"P12V_S3_AUX_CPU1_NVDIMM"
CDS_LIB"logical_power";
"A"2;
%"SCONN288_ADR50017P087CC"
"2","(1625,2800)","0","pure_quanta","I178";
;
PART_NUMBER"DFHST8FS460"
PART_TYPE"SMLF"
VALUE"SCONN288_ADR50017-P087CC"
MATERIAL"IO"
LOCATION"J18"
CDS_LIB"pure_quanta"
CDS_LMAN_SYM_OUTLINE"-600,1150,600,-1150"
NEEDS_NO_SIZE"TRUE"
$SEC"2"
CDS_SEC"2";
"DQS7_A_C||TDQS7_A_C \B"
$PN"178"29;
"DQS6_A_T||TDQS6_A_T"
$PN"168"49;
"DQS8_B_T||TDQS8_B_T"
$PN"283"57;
"DQS8_B_C||TDQS8_B_C \B"
$PN"282"38;
"DQS7_B_T||TDQS7_B_T"
$PN"272"58;
"DQS0_A_C \B"
$PN"12"36;
"DQS0_A_T"
$PN"11"55;
"DQS0_B_C \B"
$PN"105"44;
"DQS0_B_T"
$PN"104"65;
"DQS1_A_C \B"
$PN"23"35;
"DQS1_A_T"
$PN"22"54;
"DQS1_B_C \B"
$PN"116"45;
"DQS1_B_T"
$PN"115"64;
"DQS2_A_C \B"
$PN"34"34;
"DQS2_A_T"
$PN"33"53;
"DQS2_B_C \B"
$PN"127"43;
"DQS2_B_T"
$PN"126"62;
"DQS3_A_C \B"
$PN"45"33;
"DQS3_A_T"
$PN"44"52;
"DQS3_B_C \B"
$PN"138"42;
"DQS3_B_T"
$PN"137"63;
"DQS4_A_C \B"
$PN"56"32;
"DQS4_A_T"
$PN"55"51;
"DQS4_B_C \B"
$PN"238"41;
"DQS4_B_T"
$PN"239"61;
"DQS5_A_C||TDQS5_A_C||DQS5_A_T||TDQS5_A_T \B"
$PN"156"30;
"DQS5_A_T||TDQS5_A_T"
$PN"157"50;
"DQS5_B_C||TDQS5_B_C \B"
$PN"249"26;
"DQS5_B_T||TDQS5_B_T"
$PN"250"60;
"DQS6_A_C||TDQS6_A_C||DQS6_A_T||TDQS6_A_T \B"
$PN"167"31;
"DQS6_B_C||TDQS6_B_C \B"
$PN"260"40;
"DQS6_B_T||TDQS6_B_T"
$PN"261"59;
"DQS7_A_T||TDQS7_A_T"
$PN"179"48;
"DQS7_B_C||TDQS7_B_C \B"
$PN"271"39;
"DQS8_A_C||TDQS8_A_C \B"
$PN"189"28;
"DQS8_A_T||TDQS8_A_T"
$PN"190"47;
"DQS9_A_C||TDQS9_A_C \B"
$PN"200"27;
"DQS9_A_T||TDQS9_A_T"
$PN"201"46;
"DQS9_B_C||TDQS9_B_C \B"
$PN"94"37;
"DQS9_B_T||TDQS9_B_T||DBI4_B_N"
$PN"93"56;
%"Q_RES"
"1","(-2850,1075)","0","pure_quanta","I180";
;
PART_NUMBER"CS04992FB07"
VALUE"49.9"
MATERIAL"CHIP"
$LOCATION"R3892"
WATTAGE"1/16W"
TOLERANCE"1%"
PACK_TYPE"0402LF"
CDS_LIB"pure_quanta"
CDS_LOCATION"R3892"
$SEC"1"
CDS_SEC"1";
"B"
$PN"2"25;
"A"
$PN"1"22;
%"Q_RES"
"2","(-1650,-350)","0","pure_quanta","I2";
;
PART_NUMBER"CS31542FB02"
PACK_TYPE"0402LF"
MATERIAL"CHIP"
TOLERANCE"1%"
VALUE"15.4K"
WATTAGE"1/16W"
$LOCATION"R43"
CDS_LIB"pure_quanta"
CDS_LOCATION"R43"
$SEC"1"
CDS_SEC"1";
"A"
$PN"1"178;
"B"
$PN"2"9;
%"SCONN288_ADR50017P087CC"
"1","(-1050,2075)","0","pure_quanta","I24";
;
PART_NUMBER"DFHST8FS460"
PART_TYPE"SMLF"
VALUE"SCONN288_ADR50017-P087CC"
MATERIAL"IO"
$LOCATION"J18"
CDS_LIB"pure_quanta"
CDS_LMAN_SYM_OUTLINE"-450,1875,450,-1875"
NEEDS_NO_SIZE"TRUE"
CDS_LOCATION"J18"
$SEC"1"
CDS_SEC"1";
"DQ31_A"
$PN"194"177;
"CB7_A"
$PN"205"176;
"CB4_A"
$PN"58"175;
"CB1_A"
$PN"53"174;
"CB7_B"
$PN"236"173;
"ALERT_N \B"
$PN"62"23;
"CA0_A"
$PN"66"172;
"CA0_B"
$PN"76"171;
"CA1_A"
$PN"211"170;
"CA1_B"
$PN"221"169;
"CA2_A"
$PN"68"168;
"CA2_B"
$PN"78"167;
"CA3_A"
$PN"213"166;
"CA3_B"
$PN"223"165;
"CA4_A"
$PN"70"164;
"CA4_B"
$PN"80"163;
"CA5_A"
$PN"215"162;
"CA5_B"
$PN"225"161;
"CA6_A"
$PN"72"160;
"CA6_B"
$PN"82"159;
"CB6_A"
$PN"203"158;
"CB5_A"
$PN"60"157;
"CB3_A"
$PN"198"156;
"CB2_A"
$PN"196"155;
"CB0_A"
$PN"51"154;
"CB6_B"
$PN"234"153;
"CB5_B"
$PN"91"152;
"CB4_B"
$PN"89"151;
"CB3_B"
$PN"243"150;
"CB2_B"
$PN"241"149;
"CB1_B"
$PN"98"67;
"CB0_B"
$PN"96"148;
"CK_C \B"
$PN"218"147;
"CK_T"
$PN"217"146;
"CS0_A_N"
$PN"64"145;
"CS0_B_N"
$PN"84"71;
"CS1_A_N"
$PN"209"144;
"CS1_B_N"
$PN"229"143;
"DQ30_A"
$PN"192"142;
"DQ29_A"
$PN"49"141;
"DQ28_A"
$PN"47"140;
"DQ27_A"
$PN"187"139;
"DQ26_A"
$PN"185"138;
"DQ25_A"
$PN"42"137;
"DQ24_A"
$PN"40"136;
"DQ23_A"
$PN"183"135;
"DQ22_A"
$PN"181"134;
"DQ21_A"
$PN"38"133;
"DQ20_A"
$PN"36"132;
"DQ19_A"
$PN"176"131;
"DQ18_A"
$PN"174"130;
"DQ17_A"
$PN"31"129;
"DQ16_A"
$PN"29"128;
"DQ15_A"
$PN"172"127;
"DQ14_A"
$PN"170"126;
"DQ13_A"
$PN"27"125;
"DQ12_A"
$PN"25"124;
"DQ11_A"
$PN"165"123;
"DQ10_A"
$PN"163"122;
"DQ9_A"
$PN"20"121;
"DQ8_A"
$PN"18"72;
"DQ7_A"
$PN"161"120;
"DQ6_A"
$PN"159"119;
"DQ5_A"
$PN"16"118;
"DQ4_A"
$PN"14"70;
"DQ3_A"
$PN"154"117;
"DQ2_A"
$PN"152"116;
"DQ1_A"
$PN"9"115;
"DQ0_A"
$PN"7"114;
"DQ31_B"
$PN"287"113;
"DQ30_B"
$PN"285"112;
"DQ29_B"
$PN"142"111;
"DQ28_B"
$PN"140"110;
"DQ27_B"
$PN"280"66;
"DQ26_B"
$PN"278"109;
"DQ25_B"
$PN"135"108;
"DQ24_B"
$PN"133"73;
"DQ23_B"
$PN"276"107;
"DQ22_B"
$PN"274"106;
"DQ21_B"
$PN"131"105;
"DQ20_B"
$PN"129"104;
"DQ19_B"
$PN"269"103;
"DQ18_B"
$PN"267"102;
"DQ17_B"
$PN"124"101;
"DQ16_B"
$PN"122"100;
"DQ15_B"
$PN"265"99;
"DQ14_B"
$PN"263"98;
"DQ13_B"
$PN"120"97;
"DQ12_B"
$PN"118"96;
"DQ11_B"
$PN"258"95;
"DQ10_B"
$PN"256"94;
"DQ9_B"
$PN"113"93;
"DQ8_B"
$PN"111"92;
"DQ7_B"
$PN"254"91;
"DQ6_B"
$PN"252"90;
"DQ5_B"
$PN"109"89;
"DQ4_B"
$PN"107"88;
"DQ3_B"
$PN"247"87;
"DQ2_B"
$PN"245"86;
"DQ1_B"
$PN"102"85;
"DQ0_B"
$PN"100"84;
"HSA"
$PN"148"20;
"HSCL"
$PN"4"22;
"HSDA"
$PN"5"21;
"LBD||RSP_A_N"
$PN"86"83;
"LBS||RSP_B_N"
$PN"87"82;
"PAR_A"
$PN"74"68;
"PAR_B"
$PN"227"69;
"PWR_GOOD||FAIL_N"
$PN"147"81;
"RESET_N \B"
$PN"207"24;
"RFU6"
$PN"232"80;
"RFU5"
$PN"231"79;
"RFU4"
$PN"220"78;
"RFU3"
$PN"150"77;
"RFU2"
$PN"149"76;
"RFU1"
$PN"144"75;
"RFU0"
$PN"2"74;
"VIN_MGMT"
$PN"3"1;
%"TAP"
"1","(-1875,1600)","2","standard","I25";
;
CDS_LIB"standard"
BODY_TYPE"PLUMBING"
HDL_TAP"TRUE";
"B \NAC \NWC"12;
"S \NAC"
BN"0"148;
%"TAP"
"1","(-225,600)","0","standard","I26";
;
CDS_LIB"standard"
BODY_TYPE"PLUMBING"
HDL_TAP"TRUE";
"B \NAC \NWC"15;
"S \NAC"
BN"0"84;
%"TAP"
"1","(-225,650)","0","standard","I27";
;
CDS_LIB"standard"
BODY_TYPE"PLUMBING"
HDL_TAP"TRUE";
"B \NAC \NWC"15;
"S \NAC"
BN"1"85;
%"TAP"
"1","(-225,750)","0","standard","I28";
;
CDS_LIB"standard"
BODY_TYPE"PLUMBING"
HDL_TAP"TRUE";
"B \NAC \NWC"15;
"S \NAC"
BN"3"87;
%"TAP"
"1","(-225,700)","0","standard","I29";
;
CDS_LIB"standard"
BODY_TYPE"PLUMBING"
HDL_TAP"TRUE";
"B \NAC \NWC"15;
"S \NAC"
BN"2"86;
%"TAP"
"1","(-225,800)","0","standard","I30";
;
CDS_LIB"standard"
BODY_TYPE"PLUMBING"
HDL_TAP"TRUE";
"B \NAC \NWC"15;
"S \NAC"
BN"4"88;
%"TAP"
"1","(-225,850)","0","standard","I31";
;
CDS_LIB"standard"
BODY_TYPE"PLUMBING"
HDL_TAP"TRUE";
"B \NAC \NWC"15;
"S \NAC"
BN"5"89;
%"TAP"
"1","(-225,900)","0","standard","I32";
;
CDS_LIB"standard"
BODY_TYPE"PLUMBING"
HDL_TAP"TRUE";
"B \NAC \NWC"15;
"S \NAC"
BN"6"90;
%"TAP"
"1","(-225,950)","0","standard","I33";
;
CDS_LIB"standard"
BODY_TYPE"PLUMBING"
HDL_TAP"TRUE";
"B \NAC \NWC"15;
"S \NAC"
BN"7"91;
%"TAP"
"1","(-225,1000)","0","standard","I34";
;
CDS_LIB"standard"
BODY_TYPE"PLUMBING"
HDL_TAP"TRUE";
"B \NAC \NWC"15;
"S \NAC"
BN"8"92;
%"TAP"
"1","(-225,1050)","0","standard","I35";
;
CDS_LIB"standard"
BODY_TYPE"PLUMBING"
HDL_TAP"TRUE";
"B \NAC \NWC"15;
"S \NAC"
BN"9"93;
%"TAP"
"1","(-225,1100)","0","standard","I36";
;
CDS_LIB"standard"
BODY_TYPE"PLUMBING"
HDL_TAP"TRUE";
"B \NAC \NWC"15;
"S \NAC"
BN"10"94;
%"TAP"
"1","(-225,1150)","0","standard","I37";
;
CDS_LIB"standard"
BODY_TYPE"PLUMBING"
HDL_TAP"TRUE";
"B \NAC \NWC"15;
"S \NAC"
BN"11"95;
%"TAP"
"1","(-225,1200)","0","standard","I38";
;
CDS_LIB"standard"
BODY_TYPE"PLUMBING"
HDL_TAP"TRUE";
"B \NAC \NWC"15;
"S \NAC"
BN"12"96;
%"TAP"
"1","(-225,1250)","0","standard","I39";
;
CDS_LIB"standard"
BODY_TYPE"PLUMBING"
HDL_TAP"TRUE";
"B \NAC \NWC"15;
"S \NAC"
BN"13"97;
%"TAP"
"1","(-225,1350)","0","standard","I40";
;
CDS_LIB"standard"
BODY_TYPE"PLUMBING"
HDL_TAP"TRUE";
"B \NAC \NWC"15;
"S \NAC"
BN"15"99;
%"TAP"
"1","(-225,1300)","0","standard","I41";
;
CDS_LIB"standard"
BODY_TYPE"PLUMBING"
HDL_TAP"TRUE";
"B \NAC \NWC"15;
"S \NAC"
BN"14"98;
%"TAP"
"1","(-225,1450)","0","standard","I42";
;
CDS_LIB"standard"
BODY_TYPE"PLUMBING"
HDL_TAP"TRUE";
"B \NAC \NWC"15;
"S \NAC"
BN"17"101;
%"TAP"
"1","(-225,1400)","0","standard","I43";
;
CDS_LIB"standard"
BODY_TYPE"PLUMBING"
HDL_TAP"TRUE";
"B \NAC \NWC"15;
"S \NAC"
BN"16"100;
%"TAP"
"1","(-225,1500)","0","standard","I44";
;
CDS_LIB"standard"
BODY_TYPE"PLUMBING"
HDL_TAP"TRUE";
"B \NAC \NWC"15;
"S \NAC"
BN"18"102;
%"TAP"
"1","(-225,1550)","0","standard","I45";
;
CDS_LIB"standard"
BODY_TYPE"PLUMBING"
HDL_TAP"TRUE";
"B \NAC \NWC"15;
"S \NAC"
BN"19"103;
%"TAP"
"1","(-225,1600)","0","standard","I46";
;
CDS_LIB"standard"
BODY_TYPE"PLUMBING"
HDL_TAP"TRUE";
"B \NAC \NWC"15;
"S \NAC"
BN"20"104;
%"TAP"
"1","(-1875,1650)","2","standard","I47";
;
CDS_LIB"standard"
BODY_TYPE"PLUMBING"
HDL_TAP"TRUE";
"B \NAC \NWC"12;
"S \NAC"
BN"1"67;
%"TAP"
"1","(-1875,1700)","2","standard","I48";
;
CDS_LIB"standard"
BODY_TYPE"PLUMBING"
HDL_TAP"TRUE";
"B \NAC \NWC"12;
"S \NAC"
BN"2"149;
%"TAP"
"1","(-1875,1750)","2","standard","I49";
;
CDS_LIB"standard"
BODY_TYPE"PLUMBING"
HDL_TAP"TRUE";
"B \NAC \NWC"12;
"S \NAC"
BN"3"150;
%"TAP"
"1","(-1875,1800)","2","standard","I50";
;
CDS_LIB"standard"
BODY_TYPE"PLUMBING"
HDL_TAP"TRUE";
"B \NAC \NWC"12;
"S \NAC"
BN"4"151;
%"TAP"
"1","(-1875,1850)","2","standard","I51";
;
CDS_LIB"standard"
BODY_TYPE"PLUMBING"
HDL_TAP"TRUE";
"B \NAC \NWC"12;
"S \NAC"
BN"5"152;
%"TAP"
"1","(-1875,1900)","2","standard","I52";
;
CDS_LIB"standard"
BODY_TYPE"PLUMBING"
HDL_TAP"TRUE";
"B \NAC \NWC"12;
"S \NAC"
BN"6"153;
%"TAP"
"1","(-1875,1950)","2","standard","I53";
;
CDS_LIB"standard"
BODY_TYPE"PLUMBING"
HDL_TAP"TRUE";
"B \NAC \NWC"12;
"S \NAC"
BN"7"173;
%"TAP"
"1","(-1875,2050)","2","standard","I54";
;
CDS_LIB"standard"
BODY_TYPE"PLUMBING"
HDL_TAP"TRUE";
"B \NAC \NWC"11;
"S \NAC"
BN"0"154;
%"TAP"
"1","(-1875,2100)","2","standard","I55";
;
CDS_LIB"standard"
BODY_TYPE"PLUMBING"
HDL_TAP"TRUE";
"B \NAC \NWC"11;
"S \NAC"
BN"1"174;
%"TAP"
"1","(-1875,2150)","2","standard","I56";
;
CDS_LIB"standard"
BODY_TYPE"PLUMBING"
HDL_TAP"TRUE";
"B \NAC \NWC"11;
"S \NAC"
BN"2"155;
%"TAP"
"1","(-1875,2250)","2","standard","I57";
;
CDS_LIB"standard"
BODY_TYPE"PLUMBING"
HDL_TAP"TRUE";
"B \NAC \NWC"11;
"S \NAC"
BN"4"175;
%"TAP"
"1","(-1875,2200)","2","standard","I58";
;
CDS_LIB"standard"
BODY_TYPE"PLUMBING"
HDL_TAP"TRUE";
"B \NAC \NWC"11;
"S \NAC"
BN"3"156;
%"TAP"
"1","(-1875,2300)","2","standard","I59";
;
CDS_LIB"standard"
BODY_TYPE"PLUMBING"
HDL_TAP"TRUE";
"B \NAC \NWC"11;
"S \NAC"
BN"5"157;
%"TAP"
"1","(-1875,2350)","2","standard","I60";
;
CDS_LIB"standard"
BODY_TYPE"PLUMBING"
HDL_TAP"TRUE";
"B \NAC \NWC"11;
"S \NAC"
BN"6"158;
%"TAP"
"1","(-1875,2400)","2","standard","I61";
;
CDS_LIB"standard"
BODY_TYPE"PLUMBING"
HDL_TAP"TRUE";
"B \NAC \NWC"11;
"S \NAC"
BN"7"176;
%"TAP"
"1","(-1875,3150)","2","standard","I62";
;
CDS_LIB"standard"
BODY_TYPE"PLUMBING"
HDL_TAP"TRUE";
"B \NAC \NWC"14;
"S \NAC"
BN"1"169;
%"TAP"
"1","(-1875,3100)","2","standard","I63";
;
CDS_LIB"standard"
BODY_TYPE"PLUMBING"
HDL_TAP"TRUE";
"B \NAC \NWC"14;
"S \NAC"
BN"0"171;
%"TAP"
"1","(-1875,3200)","2","standard","I64";
;
CDS_LIB"standard"
BODY_TYPE"PLUMBING"
HDL_TAP"TRUE";
"B \NAC \NWC"14;
"S \NAC"
BN"2"167;
%"TAP"
"1","(-1875,3250)","2","standard","I65";
;
CDS_LIB"standard"
BODY_TYPE"PLUMBING"
HDL_TAP"TRUE";
"B \NAC \NWC"14;
"S \NAC"
BN"3"165;
%"TAP"
"1","(-1875,3300)","2","standard","I66";
;
CDS_LIB"standard"
BODY_TYPE"PLUMBING"
HDL_TAP"TRUE";
"B \NAC \NWC"14;
"S \NAC"
BN"4"163;
%"TAP"
"1","(-1875,3350)","2","standard","I67";
;
CDS_LIB"standard"
BODY_TYPE"PLUMBING"
HDL_TAP"TRUE";
"B \NAC \NWC"14;
"S \NAC"
BN"5"161;
%"TAP"
"1","(-1875,3400)","2","standard","I68";
;
CDS_LIB"standard"
BODY_TYPE"PLUMBING"
HDL_TAP"TRUE";
"B \NAC \NWC"14;
"S \NAC"
BN"6"159;
%"TAP"
"1","(-1875,3500)","2","standard","I69";
;
CDS_LIB"standard"
BODY_TYPE"PLUMBING"
HDL_TAP"TRUE";
"B \NAC \NWC"13;
"S \NAC"
BN"0"172;
%"TAP"
"1","(-1875,3550)","2","standard","I70";
;
CDS_LIB"standard"
BODY_TYPE"PLUMBING"
HDL_TAP"TRUE";
"B \NAC \NWC"13;
"S \NAC"
BN"1"170;
%"TAP"
"1","(-1875,3650)","2","standard","I71";
;
CDS_LIB"standard"
BODY_TYPE"PLUMBING"
HDL_TAP"TRUE";
"B \NAC \NWC"13;
"S \NAC"
BN"3"166;
%"TAP"
"1","(-1875,3600)","2","standard","I72";
;
CDS_LIB"standard"
BODY_TYPE"PLUMBING"
HDL_TAP"TRUE";
"B \NAC \NWC"13;
"S \NAC"
BN"2"168;
%"TAP"
"1","(-225,1700)","0","standard","I73";
;
CDS_LIB"standard"
BODY_TYPE"PLUMBING"
HDL_TAP"TRUE";
"B \NAC \NWC"15;
"S \NAC"
BN"22"106;
%"TAP"
"1","(-225,1650)","0","standard","I74";
;
CDS_LIB"standard"
BODY_TYPE"PLUMBING"
HDL_TAP"TRUE";
"B \NAC \NWC"15;
"S \NAC"
BN"21"105;
%"TAP"
"1","(-225,1750)","0","standard","I75";
;
CDS_LIB"standard"
BODY_TYPE"PLUMBING"
HDL_TAP"TRUE";
"B \NAC \NWC"15;
"S \NAC"
BN"23"107;
%"TAP"
"1","(-225,1800)","0","standard","I76";
;
CDS_LIB"standard"
BODY_TYPE"PLUMBING"
HDL_TAP"TRUE";
"B \NAC \NWC"15;
"S \NAC"
BN"24"73;
%"TAP"
"1","(-225,1850)","0","standard","I77";
;
CDS_LIB"standard"
BODY_TYPE"PLUMBING"
HDL_TAP"TRUE";
"B \NAC \NWC"15;
"S \NAC"
BN"25"108;
%"TAP"
"1","(-225,1900)","0","standard","I78";
;
CDS_LIB"standard"
BODY_TYPE"PLUMBING"
HDL_TAP"TRUE";
"B \NAC \NWC"15;
"S \NAC"
BN"26"109;
%"TAP"
"1","(-225,2000)","0","standard","I79";
;
CDS_LIB"standard"
BODY_TYPE"PLUMBING"
HDL_TAP"TRUE";
"B \NAC \NWC"15;
"S \NAC"
BN"28"110;
%"TAP"
"1","(-225,1950)","0","standard","I80";
;
CDS_LIB"standard"
BODY_TYPE"PLUMBING"
HDL_TAP"TRUE";
"B \NAC \NWC"15;
"S \NAC"
BN"27"66;
%"TAP"
"1","(-225,2050)","0","standard","I81";
;
CDS_LIB"standard"
BODY_TYPE"PLUMBING"
HDL_TAP"TRUE";
"B \NAC \NWC"15;
"S \NAC"
BN"29"111;
%"TAP"
"1","(-225,2150)","0","standard","I82";
;
CDS_LIB"standard"
BODY_TYPE"PLUMBING"
HDL_TAP"TRUE";
"B \NAC \NWC"15;
"S \NAC"
BN"31"113;
%"TAP"
"1","(-225,2100)","0","standard","I83";
;
CDS_LIB"standard"
BODY_TYPE"PLUMBING"
HDL_TAP"TRUE";
"B \NAC \NWC"15;
"S \NAC"
BN"30"112;
%"TAP"
"1","(-225,2250)","0","standard","I84";
;
CDS_LIB"standard"
BODY_TYPE"PLUMBING"
HDL_TAP"TRUE";
"B \NAC \NWC"10;
"S \NAC"
BN"0"114;
%"TAP"
"1","(-225,2350)","0","standard","I85";
;
CDS_LIB"standard"
BODY_TYPE"PLUMBING"
HDL_TAP"TRUE";
"B \NAC \NWC"10;
"S \NAC"
BN"2"116;
%"TAP"
"1","(-225,2300)","0","standard","I86";
;
CDS_LIB"standard"
BODY_TYPE"PLUMBING"
HDL_TAP"TRUE";
"B \NAC \NWC"10;
"S \NAC"
BN"1"115;
%"TAP"
"1","(-225,2400)","0","standard","I87";
;
CDS_LIB"standard"
BODY_TYPE"PLUMBING"
HDL_TAP"TRUE";
"B \NAC \NWC"10;
"S \NAC"
BN"3"117;
%"TAP"
"1","(-225,2500)","0","standard","I88";
;
CDS_LIB"standard"
BODY_TYPE"PLUMBING"
HDL_TAP"TRUE";
"B \NAC \NWC"10;
"S \NAC"
BN"5"118;
%"TAP"
"1","(-225,2450)","0","standard","I89";
;
CDS_LIB"standard"
BODY_TYPE"PLUMBING"
HDL_TAP"TRUE";
"B \NAC \NWC"10;
"S \NAC"
BN"4"70;
%"TAP"
"1","(-225,2600)","0","standard","I90";
;
CDS_LIB"standard"
BODY_TYPE"PLUMBING"
HDL_TAP"TRUE";
"B \NAC \NWC"10;
"S \NAC"
BN"7"120;
%"TAP"
"1","(-225,2550)","0","standard","I91";
;
CDS_LIB"standard"
BODY_TYPE"PLUMBING"
HDL_TAP"TRUE";
"B \NAC \NWC"10;
"S \NAC"
BN"6"119;
%"TAP"
"1","(-225,2650)","0","standard","I92";
;
CDS_LIB"standard"
BODY_TYPE"PLUMBING"
HDL_TAP"TRUE";
"B \NAC \NWC"10;
"S \NAC"
BN"8"72;
%"TAP"
"1","(-225,2700)","0","standard","I93";
;
CDS_LIB"standard"
BODY_TYPE"PLUMBING"
HDL_TAP"TRUE";
"B \NAC \NWC"10;
"S \NAC"
BN"9"121;
%"TAP"
"1","(-225,2750)","0","standard","I94";
;
CDS_LIB"standard"
BODY_TYPE"PLUMBING"
HDL_TAP"TRUE";
"B \NAC \NWC"10;
"S \NAC"
BN"10"122;
%"TAP"
"1","(-225,2800)","0","standard","I95";
;
CDS_LIB"standard"
BODY_TYPE"PLUMBING"
HDL_TAP"TRUE";
"B \NAC \NWC"10;
"S \NAC"
BN"11"123;
%"TAP"
"1","(-225,2900)","0","standard","I96";
;
CDS_LIB"standard"
BODY_TYPE"PLUMBING"
HDL_TAP"TRUE";
"B \NAC \NWC"10;
"S \NAC"
BN"13"125;
%"TAP"
"1","(-225,2850)","0","standard","I97";
;
CDS_LIB"standard"
BODY_TYPE"PLUMBING"
HDL_TAP"TRUE";
"B \NAC \NWC"10;
"S \NAC"
BN"12"124;
%"TAP"
"1","(-225,2950)","0","standard","I98";
;
CDS_LIB"standard"
BODY_TYPE"PLUMBING"
HDL_TAP"TRUE";
"B \NAC \NWC"10;
"S \NAC"
BN"14"126;
%"TAP"
"1","(-225,3000)","0","standard","I99";
;
CDS_LIB"standard"
BODY_TYPE"PLUMBING"
HDL_TAP"TRUE";
"B \NAC \NWC"10;
"S \NAC"
BN"15"127;
END.
